# BASEBOARD_FAB2 (Tioga Pass) — schematic netlist excerpt (pin names and nets, part order shuffled) for the footprints in the layout excerpt that follows; sources: Cadence DE-HDL packaged netlist, KiCad conversion of Wiwynn_Tioga_Pass_MB.brd

C6U18  CAP  10UF 16V 10% X7R  pkg 0805  page 197 : A = P12V_NVDIMM_ABC ; B = GND
C8M12  CAP_A  47UF 4V 20% X5R  pkg 0603V  page 230 : A = PVTT_KLM ; B = GND
C8L8  CAP_A  47UF 4V 20% X5R  pkg 0603V  page 228 : A = PVDDQ_KLM ; B = GND

(kicad_pcb
	(version 20260206)
	(generator "pcbnew")
	(generator_version "10.0")
	(general
		(thickness 1.6)
		(legacy_teardrops no)
	)
	(paper "A4")
	(title_block
		(title "Wiwynn_Tioga_Pass_MB.brd")
		(comment 1 "Tioga Pass / footprints 2697-2699 of 4770")
	)
	(layers
		(0 "F.Cu" signal "TOP")
		(4 "In1.Cu" signal "L2GND")
		(6 "In2.Cu" signal "L3")
		(8 "In3.Cu" signal "L4GND")
		(10 "In4.Cu" signal "L5")
		(12 "In5.Cu" signal "L6GND")
		(14 "In6.Cu" signal "L7VCC")
		(16 "In7.Cu" signal "L8VCC")
		(18 "In8.Cu" signal "L9GND")
		(20 "In9.Cu" signal "L10")
		(22 "In10.Cu" signal "L11GND")
		(24 "In11.Cu" signal "L12")
		(26 "In12.Cu" signal "L13GND")
		(2 "B.Cu" signal "BOTTOM")
		(9 "F.Adhes" user "F.Adhesive")
		(11 "B.Adhes" user "B.Adhesive")
		(13 "F.Paste" user "Package Geometry/Pastemask Top")
		(15 "B.Paste" user "Package Geometry/Pastemask Bottom")
		(5 "F.SilkS" user "Ref Des/Silkscreen Top")
		(7 "B.SilkS" user "Ref Des/Silkscreen Bottom")
		(1 "F.Mask" user "Board Geometry/Soldermask Top")
		(3 "B.Mask" user "Board Geometry/Soldermask Bottom")
		(17 "Dwgs.User" user "User.Drawings")
		(19 "Cmts.User" user "User.Comments")
		(21 "Eco1.User" user "User.Eco1")
		(23 "Eco2.User" user "User.Eco2")
		(25 "Edge.Cuts" user "Board Geometry/Outline")
		(27 "Margin" user)
		(31 "F.CrtYd" user "Package Geometry/Place Bound Top")
		(29 "B.CrtYd" user "Package Geometry/Place Bound Bottom")
		(35 "F.Fab" user "Ref Des/Assembly Top")
		(33 "B.Fab" user "Ref Des/Assembly Bottom")
	)
	(footprint ""
		(layer "B.Cu")
		(at 193.092832 2.1336 -90)
		(property "Reference" "C6U18"
			(at 0 0 90)
			(layer "B.SilkS")
			(hide yes)
			(effects
				(font
					(size 1.27 1.27)
				)
				(justify mirror)
			)
		)
		(property "Value" ""
			(at 0 0 90)
			(layer "B.Fab")
			(effects
				(font
					(size 1.27 1.27)
				)
				(justify mirror)
			)
		)
		(duplicate_pad_numbers_are_jumpers no)
		(fp_rect
			(start -0.7239 1.9939)
			(end 0.7239 -0.2159)
			(stroke
				(width 0)
				(type default)
			)
			(fill no)
			(layer "B.CrtYd")
		)
		(fp_line
			(start -0.7239 1.9939)
			(end -0.7239 -0.2159)
			(stroke
				(width 0.1)
				(type default)
			)
			(layer "B.Fab")
		)
		(fp_line
			(start 0.7239 1.9939)
			(end -0.7239 1.9939)
			(stroke
				(width 0.1)
				(type default)
			)
			(layer "B.Fab")
		)
		(fp_line
			(start -0.7239 -0.2159)
			(end 0.7239 -0.2159)
			(stroke
				(width 0.1)
				(type default)
			)
			(layer "B.Fab")
		)
		(fp_line
			(start 0.7239 -0.2159)
			(end 0.7239 1.9939)
			(stroke
				(width 0.1)
				(type default)
			)
			(layer "B.Fab")
		)
		(pad "1" smd rect
			(at 0 0 90)
			(size 1.27 1.016)
			(layers "B.Cu" "B.Mask" "B.Paste")
			(net "P12V_NVDIMM_ABC")
		)
		(pad "2" smd rect
			(at 0 1.778 90)
			(size 1.27 1.016)
			(layers "B.Cu" "B.Mask" "B.Paste")
			(net "GND")
		)
		(zone
			(layer "B.Cu")
			(hatch none 0.5)
			(connect_pads
				(clearance 0)
			)
			(min_thickness 0.25)
			(keepout
				(tracks not_allowed)
				(vias allowed)
				(pads allowed)
				(copperpour not_allowed)
				(footprints allowed)
			)
			(placement
				(enabled no)
				(sheetname "")
			)
			(fill
				(thermal_gap 0.5)
				(thermal_bridge_width 0.5)
				(island_removal_mode 0)
			)
			(polygon
				(pts
					(xy 191.822832 1.4986) (xy 191.822832 2.7686) (xy 192.584832 2.7686) (xy 192.584832 1.4986)
				)
			)
		)
	)
	(footprint ""
		(layer "B.Cu")
		(at 87.158068 -145.0086 -90)
		(property "Reference" "C8L8"
			(at -1.848866 0.752348 270)
			(unlocked yes)
			(layer "B.SilkS")
			(effects
				(font
					(size 1.27 0.9652)
					(thickness 0.1524)
				)
				(justify mirror)
			)
		)
		(property "Value" ""
			(at 0 0 90)
			(layer "B.Fab")
			(effects
				(font
					(size 1.27 1.27)
				)
				(justify mirror)
			)
		)
		(duplicate_pad_numbers_are_jumpers no)
		(fp_rect
			(start 0.500126 1.598422)
			(end -0.500126 -0.201422)
			(stroke
				(width 0)
				(type default)
			)
			(fill no)
			(layer "B.CrtYd")
		)
		(fp_line
			(start -0.500126 1.598422)
			(end 0.500126 1.598422)
			(stroke
				(width 0.1)
				(type default)
			)
			(layer "B.Fab")
		)
		(fp_line
			(start 0.500126 1.598422)
			(end 0.500126 -0.201422)
			(stroke
				(width 0.1)
				(type default)
			)
			(layer "B.Fab")
		)
		(fp_line
			(start -0.500126 -0.201422)
			(end -0.500126 1.598422)
			(stroke
				(width 0.1)
				(type default)
			)
			(layer "B.Fab")
		)
		(fp_line
			(start 0.500126 -0.201422)
			(end -0.500126 -0.201422)
			(stroke
				(width 0.1)
				(type default)
			)
			(layer "B.Fab")
		)
		(pad "1" smd rect
			(at 0 0 180)
			(size 0.889 0.9906)
			(layers "B.Cu" "B.Mask" "B.Paste")
			(net "PVDDQ_KLM")
		)
		(pad "2" smd rect
			(at 0 1.397 180)
			(size 0.889 0.9906)
			(layers "B.Cu" "B.Mask" "B.Paste")
			(net "GND")
		)
		(zone
			(layer "B.Cu")
			(hatch none 0.5)
			(connect_pads
				(clearance 0)
			)
			(min_thickness 0.25)
			(keepout
				(tracks allowed)
				(vias not_allowed)
				(pads allowed)
				(copperpour not_allowed)
				(footprints allowed)
			)
			(placement
				(enabled no)
				(sheetname "")
			)
			(fill
				(thermal_gap 0.5)
				(thermal_bridge_width 0.5)
				(island_removal_mode 0)
			)
			(polygon
				(pts
					(xy 86.205568 -144.5133) (xy 86.713568 -144.5133) (xy 86.713568 -145.5039) (xy 86.205568 -145.5039)
				)
			)
		)
		(zone
			(layer "B.Cu")
			(hatch none 0.5)
			(connect_pads
				(clearance 0)
			)
			(min_thickness 0.25)
			(keepout
				(tracks not_allowed)
				(vias allowed)
				(pads allowed)
				(copperpour not_allowed)
				(footprints allowed)
			)
			(placement
				(enabled no)
				(sheetname "")
			)
			(fill
				(thermal_gap 0.5)
				(thermal_bridge_width 0.5)
				(island_removal_mode 0)
			)
			(polygon
				(pts
					(xy 86.205568 -144.5133) (xy 86.713568 -144.5133) (xy 86.713568 -145.5039) (xy 86.205568 -145.5039)
				)
			)
		)
	)
	(footprint ""
		(layer "B.Cu")
		(at 96.03232 -126.43358 90)
		(property "Reference" "C8M12"
			(at -1.66497 0.408432 0)
			(unlocked yes)
			(layer "B.SilkS")
			(effects
				(font
					(size 0.7874 0.5842)
					(thickness 0.1524)
				)
				(justify mirror)
			)
		)
		(property "Value" ""
			(at 0 0 90)
			(layer "B.Fab")
			(effects
				(font
					(size 1.27 1.27)
				)
				(justify mirror)
			)
		)
		(duplicate_pad_numbers_are_jumpers no)
		(fp_rect
			(start 0.500126 1.598422)
			(end -0.500126 -0.201422)
			(stroke
				(width 0)
				(type default)
			)
			(fill no)
			(layer "B.CrtYd")
		)
		(fp_line
			(start 0.500126 -0.201422)
			(end -0.500126 -0.201422)
			(stroke
				(width 0.1)
				(type default)
			)
			(layer "B.Fab")
		)
		(fp_line
			(start -0.500126 -0.201422)
			(end -0.500126 1.598422)
			(stroke
				(width 0.1)
				(type default)
			)
			(layer "B.Fab")
		)
		(fp_line
			(start 0.500126 1.598422)
			(end 0.500126 -0.201422)
			(stroke
				(width 0.1)
				(type default)
			)
			(layer "B.Fab")
		)
		(fp_line
			(start -0.500126 1.598422)
			(end 0.500126 1.598422)
			(stroke
				(width 0.1)
				(type default)
			)
			(layer "B.Fab")
		)
		(pad "1" smd rect
			(at 0 0)
			(size 0.889 0.9906)
			(layers "B.Cu" "B.Mask" "B.Paste")
			(net "PVTT_KLM")
		)
		(pad "2" smd rect
			(at 0 1.397)
			(size 0.889 0.9906)
			(layers "B.Cu" "B.Mask" "B.Paste")
			(net "GND")
		)
		(zone
			(layer "B.Cu")
			(hatch none 0.5)
			(connect_pads
				(clearance 0)
			)
			(min_thickness 0.25)
			(keepout
				(tracks not_allowed)
				(vias allowed)
				(pads allowed)
				(copperpour not_allowed)
				(footprints allowed)
			)
			(placement
				(enabled no)
				(sheetname "")
			)
			(fill
				(thermal_gap 0.5)
				(thermal_bridge_width 0.5)
				(island_removal_mode 0)
			)
			(polygon
				(pts
					(xy 96.98482 -126.92888) (xy 96.47682 -126.92888) (xy 96.47682 -125.93828) (xy 96.98482 -125.93828)
				)
			)
		)
		(zone
			(layer "B.Cu")
			(hatch none 0.5)
			(connect_pads
				(clearance 0)
			)
			(min_thickness 0.25)
			(keepout
				(tracks allowed)
				(vias not_allowed)
				(pads allowed)
				(copperpour not_allowed)
				(footprints allowed)
			)
			(placement
				(enabled no)
				(sheetname "")
			)
			(fill
				(thermal_gap 0.5)
				(thermal_bridge_width 0.5)
				(island_removal_mode 0)
			)
			(polygon
				(pts
					(xy 96.98482 -126.92888) (xy 96.47682 -126.92888) (xy 96.47682 -125.93828) (xy 96.98482 -125.93828)
				)
			)
		)
	)
)
